(kicad_pcb
	(version 20260206)
	(generator "pcbnew")
	(generator_version "10.0")
	(general
		(thickness 1.6)
		(legacy_teardrops no)
	)
	(paper "A4")
	(title_block
		(title "12092022_DA0F0TMDCD0_F0T_Management_Board_D_brd_V3_OCP.brd")
		(comment 1 "Grand Teton / footprints 666-671 of 1440")
	)
	(layers
		(0 "F.Cu" signal "TOP")
		(4 "In1.Cu" signal "GND")
		(6 "In2.Cu" signal "IN1")
		(8 "In3.Cu" signal "GND1")
		(10 "In4.Cu" signal "IN2")
		(12 "In5.Cu" signal "VCC")
		(14 "In6.Cu" signal "VCC1")
		(16 "In7.Cu" signal "IN3")
		(18 "In8.Cu" signal "GND2")
		(20 "In9.Cu" signal "IN4")
		(22 "In10.Cu" signal "GND3")
		(2 "B.Cu" signal "BOTTOM")
		(9 "F.Adhes" user "F.Adhesive")
		(11 "B.Adhes" user "B.Adhesive")
		(13 "F.Paste" user "Package Geometry/Pastemask Top")
		(15 "B.Paste" user "Package Geometry/Pastemask Bottom")
		(5 "F.SilkS" user "Ref Des/Silkscreen Top")
		(7 "B.SilkS" user "Ref Des/Silkscreen Bottom")
		(1 "F.Mask" user "Board Geometry/Soldermask Top")
		(3 "B.Mask" user "Board Geometry/Soldermask Bottom")
		(17 "Dwgs.User" user "User.Drawings")
		(19 "Cmts.User" user "User.Comments")
		(21 "Eco1.User" user "User.Eco1")
		(23 "Eco2.User" user "User.Eco2")
		(25 "Edge.Cuts" user "Board Geometry/Outline")
		(27 "Margin" user)
		(31 "F.CrtYd" user "Package Geometry/Place Bound Top")
		(29 "B.CrtYd" user "Package Geometry/Place Bound Bottom")
		(35 "F.Fab" user "Ref Des/Assembly Top")
		(33 "B.Fab" user "Ref Des/Assembly Bottom")
	)
	(footprint ""
		(layer "F.Cu")
		(at 72.25665 -94.871032 -90)
		(property "Reference" "R59"
			(at 0 0 270)
			(layer "F.SilkS")
			(hide yes)
			(effects
				(font
					(size 1.27 1.27)
				)
			)
		)
		(property "Value" ""
			(at 0 0 270)
			(layer "F.Fab")
			(effects
				(font
					(size 1.27 1.27)
				)
			)
		)
		(duplicate_pad_numbers_are_jumpers no)
		(fp_line
			(start -0.7874 0.4064)
			(end -0.7874 -0.4064)
			(stroke
				(width 0.1524)
				(type default)
			)
			(layer "F.SilkS")
		)
		(fp_line
			(start 0.7874 0.4064)
			(end -0.7874 0.4064)
			(stroke
				(width 0.1524)
				(type default)
			)
			(layer "F.SilkS")
		)
		(fp_line
			(start -0.7874 -0.4064)
			(end 0.7874 -0.4064)
			(stroke
				(width 0.1524)
				(type default)
			)
			(layer "F.SilkS")
		)
		(fp_line
			(start 0.7874 -0.4064)
			(end 0.7874 0.4064)
			(stroke
				(width 0.1524)
				(type default)
			)
			(layer "F.SilkS")
		)
		(fp_line
			(start -0.67945 0.3048)
			(end -0.67945 -0.305054)
			(stroke
				(width 0.1)
				(type default)
			)
			(layer "F.Fab")
		)
		(fp_line
			(start -0.12065 0.3048)
			(end -0.67945 0.3048)
			(stroke
				(width 0.1)
				(type default)
			)
			(layer "F.Fab")
		)
		(fp_line
			(start 0.120396 0.3048)
			(end 0.120396 0.2794)
			(stroke
				(width 0.1)
				(type default)
			)
			(layer "F.Fab")
		)
		(fp_line
			(start 0.67945 0.3048)
			(end 0.120396 0.3048)
			(stroke
				(width 0.1)
				(type default)
			)
			(layer "F.Fab")
		)
		(fp_line
			(start -0.12065 0.2794)
			(end -0.12065 0.3048)
			(stroke
				(width 0.1)
				(type default)
			)
			(layer "F.Fab")
		)
		(fp_line
			(start 0.120396 0.2794)
			(end -0.12065 0.2794)
			(stroke
				(width 0.1)
				(type default)
			)
			(layer "F.Fab")
		)
		(fp_line
			(start -0.12065 -0.2794)
			(end 0.12065 -0.2794)
			(stroke
				(width 0.1)
				(type default)
			)
			(layer "F.Fab")
		)
		(fp_line
			(start 0.12065 -0.2794)
			(end 0.12065 -0.3048)
			(stroke
				(width 0.1)
				(type default)
			)
			(layer "F.Fab")
		)
		(fp_line
			(start 0.12065 -0.3048)
			(end 0.67945 -0.3048)
			(stroke
				(width 0.1)
				(type default)
			)
			(layer "F.Fab")
		)
		(fp_line
			(start 0.67945 -0.3048)
			(end 0.67945 0.3048)
			(stroke
				(width 0.1)
				(type default)
			)
			(layer "F.Fab")
		)
		(fp_line
			(start -0.67945 -0.305054)
			(end -0.12065 -0.305054)
			(stroke
				(width 0.1)
				(type default)
			)
			(layer "F.Fab")
		)
		(fp_line
			(start -0.12065 -0.305054)
			(end -0.12065 -0.2794)
			(stroke
				(width 0.1)
				(type default)
			)
			(layer "F.Fab")
		)
		(pad "1" smd circle
			(at -0.40005 0 270)
			(size 0 0)
			(layers "F.Cu" "F.Mask" "F.Paste")
			(net "P3V3_AUX")
		)
		(pad "2" smd circle
			(at 0.40005 0 270)
			(size 0 0)
			(layers "F.Cu" "F.Mask" "F.Paste")
			(net "IRQ_TPM_SPI_N")
		)
	)
	(footprint ""
		(layer "F.Cu")
		(at 33.629092 -57.452768 -90)
		(property "Reference" "R393"
			(at 0 0 270)
			(layer "F.SilkS")
			(hide yes)
			(effects
				(font
					(size 1.27 1.27)
				)
			)
		)
		(property "Value" ""
			(at 0 0 270)
			(layer "F.Fab")
			(effects
				(font
					(size 1.27 1.27)
				)
			)
		)
		(duplicate_pad_numbers_are_jumpers no)
		(fp_line
			(start -0.7874 0.4064)
			(end -0.7874 -0.4064)
			(stroke
				(width 0.1524)
				(type default)
			)
			(layer "F.SilkS")
		)
		(fp_line
			(start 0.7874 0.4064)
			(end -0.7874 0.4064)
			(stroke
				(width 0.1524)
				(type default)
			)
			(layer "F.SilkS")
		)
		(fp_line
			(start -0.7874 -0.4064)
			(end 0.7874 -0.4064)
			(stroke
				(width 0.1524)
				(type default)
			)
			(layer "F.SilkS")
		)
		(fp_line
			(start 0.7874 -0.4064)
			(end 0.7874 0.4064)
			(stroke
				(width 0.1524)
				(type default)
			)
			(layer "F.SilkS")
		)
		(fp_line
			(start -0.67945 0.3048)
			(end -0.67945 -0.305054)
			(stroke
				(width 0.1)
				(type default)
			)
			(layer "F.Fab")
		)
		(fp_line
			(start -0.12065 0.3048)
			(end -0.67945 0.3048)
			(stroke
				(width 0.1)
				(type default)
			)
			(layer "F.Fab")
		)
		(fp_line
			(start 0.120396 0.3048)
			(end 0.120396 0.2794)
			(stroke
				(width 0.1)
				(type default)
			)
			(layer "F.Fab")
		)
		(fp_line
			(start 0.67945 0.3048)
			(end 0.120396 0.3048)
			(stroke
				(width 0.1)
				(type default)
			)
			(layer "F.Fab")
		)
		(fp_line
			(start -0.12065 0.2794)
			(end -0.12065 0.3048)
			(stroke
				(width 0.1)
				(type default)
			)
			(layer "F.Fab")
		)
		(fp_line
			(start 0.120396 0.2794)
			(end -0.12065 0.2794)
			(stroke
				(width 0.1)
				(type default)
			)
			(layer "F.Fab")
		)
		(fp_line
			(start -0.12065 -0.2794)
			(end 0.12065 -0.2794)
			(stroke
				(width 0.1)
				(type default)
			)
			(layer "F.Fab")
		)
		(fp_line
			(start 0.12065 -0.2794)
			(end 0.12065 -0.3048)
			(stroke
				(width 0.1)
				(type default)
			)
			(layer "F.Fab")
		)
		(fp_line
			(start 0.12065 -0.3048)
			(end 0.67945 -0.3048)
			(stroke
				(width 0.1)
				(type default)
			)
			(layer "F.Fab")
		)
		(fp_line
			(start 0.67945 -0.3048)
			(end 0.67945 0.3048)
			(stroke
				(width 0.1)
				(type default)
			)
			(layer "F.Fab")
		)
		(fp_line
			(start -0.67945 -0.305054)
			(end -0.12065 -0.305054)
			(stroke
				(width 0.1)
				(type default)
			)
			(layer "F.Fab")
		)
		(fp_line
			(start -0.12065 -0.305054)
			(end -0.12065 -0.2794)
			(stroke
				(width 0.1)
				(type default)
			)
			(layer "F.Fab")
		)
		(pad "1" smd circle
			(at -0.40005 0 270)
			(size 0 0)
			(layers "F.Cu" "F.Mask" "F.Paste")
			(net "EN_P1V8")
		)
		(pad "2" smd circle
			(at 0.40005 0 270)
			(size 0 0)
			(layers "F.Cu" "F.Mask" "F.Paste")
			(net "EN_P1V8_R")
		)
	)
	(footprint ""
		(layer "F.Cu")
		(at 12.7762 -66.2432 180)
		(property "Reference" "PR242"
			(at 0 0 180)
			(layer "F.SilkS")
			(hide yes)
			(effects
				(font
					(size 1.27 1.27)
				)
			)
		)
		(property "Value" ""
			(at 0 0 180)
			(layer "F.Fab")
			(effects
				(font
					(size 1.27 1.27)
				)
			)
		)
		(duplicate_pad_numbers_are_jumpers no)
		(fp_line
			(start 0.7874 0.4064)
			(end -0.7874 0.4064)
			(stroke
				(width 0.1524)
				(type default)
			)
			(layer "F.SilkS")
		)
		(fp_line
			(start 0.7874 -0.4064)
			(end 0.7874 0.4064)
			(stroke
				(width 0.1524)
				(type default)
			)
			(layer "F.SilkS")
		)
		(fp_line
			(start -0.7874 0.4064)
			(end -0.7874 -0.4064)
			(stroke
				(width 0.1524)
				(type default)
			)
			(layer "F.SilkS")
		)
		(fp_line
			(start -0.7874 -0.4064)
			(end 0.7874 -0.4064)
			(stroke
				(width 0.1524)
				(type default)
			)
			(layer "F.SilkS")
		)
		(fp_line
			(start 0.67945 0.3048)
			(end 0.120396 0.3048)
			(stroke
				(width 0.1)
				(type default)
			)
			(layer "F.Fab")
		)
		(fp_line
			(start 0.67945 -0.3048)
			(end 0.67945 0.3048)
			(stroke
				(width 0.1)
				(type default)
			)
			(layer "F.Fab")
		)
		(fp_line
			(start 0.12065 -0.2794)
			(end 0.12065 -0.3048)
			(stroke
				(width 0.1)
				(type default)
			)
			(layer "F.Fab")
		)
		(fp_line
			(start 0.12065 -0.3048)
			(end 0.67945 -0.3048)
			(stroke
				(width 0.1)
				(type default)
			)
			(layer "F.Fab")
		)
		(fp_line
			(start 0.120396 0.3048)
			(end 0.120396 0.2794)
			(stroke
				(width 0.1)
				(type default)
			)
			(layer "F.Fab")
		)
		(fp_line
			(start 0.120396 0.2794)
			(end -0.12065 0.2794)
			(stroke
				(width 0.1)
				(type default)
			)
			(layer "F.Fab")
		)
		(fp_line
			(start -0.12065 0.3048)
			(end -0.67945 0.3048)
			(stroke
				(width 0.1)
				(type default)
			)
			(layer "F.Fab")
		)
		(fp_line
			(start -0.12065 0.2794)
			(end -0.12065 0.3048)
			(stroke
				(width 0.1)
				(type default)
			)
			(layer "F.Fab")
		)
		(fp_line
			(start -0.12065 -0.2794)
			(end 0.12065 -0.2794)
			(stroke
				(width 0.1)
				(type default)
			)
			(layer "F.Fab")
		)
		(fp_line
			(start -0.12065 -0.305054)
			(end -0.12065 -0.2794)
			(stroke
				(width 0.1)
				(type default)
			)
			(layer "F.Fab")
		)
		(fp_line
			(start -0.67945 0.3048)
			(end -0.67945 -0.305054)
			(stroke
				(width 0.1)
				(type default)
			)
			(layer "F.Fab")
		)
		(fp_line
			(start -0.67945 -0.305054)
			(end -0.12065 -0.305054)
			(stroke
				(width 0.1)
				(type default)
			)
			(layer "F.Fab")
		)
		(pad "1" smd circle
			(at -0.40005 0 180)
			(size 0 0)
			(layers "F.Cu" "F.Mask" "F.Paste")
			(net "P3V3_AUX")
		)
		(pad "2" smd circle
			(at 0.40005 0 180)
			(size 0 0)
			(layers "F.Cu" "F.Mask" "F.Paste")
			(net "PWRGD_P3V3_AUX_R")
		)
	)
	(footprint ""
		(layer "F.Cu")
		(at 18.923 -69.977 -90)
		(property "Reference" "C235"
			(at 0 0 270)
			(layer "F.SilkS")
			(hide yes)
			(effects
				(font
					(size 1.27 1.27)
				)
			)
		)
		(property "Value" ""
			(at 0 0 270)
			(layer "F.Fab")
			(effects
				(font
					(size 1.27 1.27)
				)
			)
		)
		(duplicate_pad_numbers_are_jumpers no)
		(fp_line
			(start -0.7874 0.4064)
			(end -0.7874 -0.4064)
			(stroke
				(width 0.1524)
				(type default)
			)
			(layer "F.SilkS")
		)
		(fp_line
			(start 0.7874 0.4064)
			(end -0.7874 0.4064)
			(stroke
				(width 0.1524)
				(type default)
			)
			(layer "F.SilkS")
		)
		(fp_line
			(start -0.7874 -0.4064)
			(end 0.7874 -0.4064)
			(stroke
				(width 0.1524)
				(type default)
			)
			(layer "F.SilkS")
		)
		(fp_line
			(start 0.7874 -0.4064)
			(end 0.7874 0.4064)
			(stroke
				(width 0.1524)
				(type default)
			)
			(layer "F.SilkS")
		)
		(fp_line
			(start -0.67945 0.3048)
			(end -0.67945 -0.305054)
			(stroke
				(width 0.1)
				(type default)
			)
			(layer "F.Fab")
		)
		(fp_line
			(start -0.12065 0.3048)
			(end -0.67945 0.3048)
			(stroke
				(width 0.1)
				(type default)
			)
			(layer "F.Fab")
		)
		(fp_line
			(start 0.120396 0.3048)
			(end 0.120396 0.2794)
			(stroke
				(width 0.1)
				(type default)
			)
			(layer "F.Fab")
		)
		(fp_line
			(start 0.67945 0.3048)
			(end 0.120396 0.3048)
			(stroke
				(width 0.1)
				(type default)
			)
			(layer "F.Fab")
		)
		(fp_line
			(start -0.12065 0.2794)
			(end -0.12065 0.3048)
			(stroke
				(width 0.1)
				(type default)
			)
			(layer "F.Fab")
		)
		(fp_line
			(start 0.120396 0.2794)
			(end -0.12065 0.2794)
			(stroke
				(width 0.1)
				(type default)
			)
			(layer "F.Fab")
		)
		(fp_line
			(start -0.12065 -0.2794)
			(end 0.12065 -0.2794)
			(stroke
				(width 0.1)
				(type default)
			)
			(layer "F.Fab")
		)
		(fp_line
			(start 0.12065 -0.2794)
			(end 0.12065 -0.3048)
			(stroke
				(width 0.1)
				(type default)
			)
			(layer "F.Fab")
		)
		(fp_line
			(start 0.12065 -0.3048)
			(end 0.67945 -0.3048)
			(stroke
				(width 0.1)
				(type default)
			)
			(layer "F.Fab")
		)
		(fp_line
			(start 0.67945 -0.3048)
			(end 0.67945 0.3048)
			(stroke
				(width 0.1)
				(type default)
			)
			(layer "F.Fab")
		)
		(fp_line
			(start -0.67945 -0.305054)
			(end -0.12065 -0.305054)
			(stroke
				(width 0.1)
				(type default)
			)
			(layer "F.Fab")
		)
		(fp_line
			(start -0.12065 -0.305054)
			(end -0.12065 -0.2794)
			(stroke
				(width 0.1)
				(type default)
			)
			(layer "F.Fab")
		)
		(pad "1" smd circle
			(at -0.40005 0 270)
			(size 0 0)
			(layers "F.Cu" "F.Mask" "F.Paste")
			(net "P3V3_AUX")
		)
		(pad "2" smd circle
			(at 0.40005 0 270)
			(size 0 0)
			(layers "F.Cu" "F.Mask" "F.Paste")
			(net "GND")
		)
	)
	(footprint ""
		(layer "F.Cu")
		(at 41.0083 -109.474 -90)
		(property "Reference" "R78"
			(at 0 0 270)
			(layer "F.SilkS")
			(hide yes)
			(effects
				(font
					(size 1.27 1.27)
				)
			)
		)
		(property "Value" ""
			(at 0 0 270)
			(layer "F.Fab")
			(effects
				(font
					(size 1.27 1.27)
				)
			)
		)
		(duplicate_pad_numbers_are_jumpers no)
		(fp_line
			(start -0.7874 0.4064)
			(end -0.7874 -0.4064)
			(stroke
				(width 0.1524)
				(type default)
			)
			(layer "F.SilkS")
		)
		(fp_line
			(start 0.7874 0.4064)
			(end -0.7874 0.4064)
			(stroke
				(width 0.1524)
				(type default)
			)
			(layer "F.SilkS")
		)
		(fp_line
			(start -0.7874 -0.4064)
			(end 0.7874 -0.4064)
			(stroke
				(width 0.1524)
				(type default)
			)
			(layer "F.SilkS")
		)
		(fp_line
			(start 0.7874 -0.4064)
			(end 0.7874 0.4064)
			(stroke
				(width 0.1524)
				(type default)
			)
			(layer "F.SilkS")
		)
		(fp_line
			(start -0.67945 0.3048)
			(end -0.67945 -0.305054)
			(stroke
				(width 0.1)
				(type default)
			)
			(layer "F.Fab")
		)
		(fp_line
			(start -0.12065 0.3048)
			(end -0.67945 0.3048)
			(stroke
				(width 0.1)
				(type default)
			)
			(layer "F.Fab")
		)
		(fp_line
			(start 0.120396 0.3048)
			(end 0.120396 0.2794)
			(stroke
				(width 0.1)
				(type default)
			)
			(layer "F.Fab")
		)
		(fp_line
			(start 0.67945 0.3048)
			(end 0.120396 0.3048)
			(stroke
				(width 0.1)
				(type default)
			)
			(layer "F.Fab")
		)
		(fp_line
			(start -0.12065 0.2794)
			(end -0.12065 0.3048)
			(stroke
				(width 0.1)
				(type default)
			)
			(layer "F.Fab")
		)
		(fp_line
			(start 0.120396 0.2794)
			(end -0.12065 0.2794)
			(stroke
				(width 0.1)
				(type default)
			)
			(layer "F.Fab")
		)
		(fp_line
			(start -0.12065 -0.2794)
			(end 0.12065 -0.2794)
			(stroke
				(width 0.1)
				(type default)
			)
			(layer "F.Fab")
		)
		(fp_line
			(start 0.12065 -0.2794)
			(end 0.12065 -0.3048)
			(stroke
				(width 0.1)
				(type default)
			)
			(layer "F.Fab")
		)
		(fp_line
			(start 0.12065 -0.3048)
			(end 0.67945 -0.3048)
			(stroke
				(width 0.1)
				(type default)
			)
			(layer "F.Fab")
		)
		(fp_line
			(start 0.67945 -0.3048)
			(end 0.67945 0.3048)
			(stroke
				(width 0.1)
				(type default)
			)
			(layer "F.Fab")
		)
		(fp_line
			(start -0.67945 -0.305054)
			(end -0.12065 -0.305054)
			(stroke
				(width 0.1)
				(type default)
			)
			(layer "F.Fab")
		)
		(fp_line
			(start -0.12065 -0.305054)
			(end -0.12065 -0.2794)
			(stroke
				(width 0.1)
				(type default)
			)
			(layer "F.Fab")
		)
		(pad "1" smd circle
			(at -0.40005 0 270)
			(size 0 0)
			(layers "F.Cu" "F.Mask" "F.Paste")
			(net "P3V3_AUX")
		)
		(pad "2" smd circle
			(at 0.40005 0 270)
			(size 0 0)
			(layers "F.Cu" "F.Mask" "F.Paste")
			(net "SGPIO_DI_0")
		)
	)
	(footprint ""
		(layer "F.Cu")
		(at 23.1775 -105.918)
		(property "Reference" "R314"
			(at 0 0 0)
			(layer "F.SilkS")
			(hide yes)
			(effects
				(font
					(size 1.27 1.27)
				)
			)
		)
		(property "Value" ""
			(at 0 0 0)
			(layer "F.Fab")
			(effects
				(font
					(size 1.27 1.27)
				)
			)
		)
		(duplicate_pad_numbers_are_jumpers no)
		(fp_line
			(start -0.7874 -0.4064)
			(end 0.7874 -0.4064)
			(stroke
				(width 0.1524)
				(type default)
			)
			(layer "F.SilkS")
		)
		(fp_line
			(start -0.7874 0.4064)
			(end -0.7874 -0.4064)
			(stroke
				(width 0.1524)
				(type default)
			)
			(layer "F.SilkS")
		)
		(fp_line
			(start 0.7874 -0.4064)
			(end 0.7874 0.4064)
			(stroke
				(width 0.1524)
				(type default)
			)
			(layer "F.SilkS")
		)
		(fp_line
			(start 0.7874 0.4064)
			(end -0.7874 0.4064)
			(stroke
				(width 0.1524)
				(type default)
			)
			(layer "F.SilkS")
		)
		(fp_line
			(start -0.67945 -0.305054)
			(end -0.12065 -0.305054)
			(stroke
				(width 0.1)
				(type default)
			)
			(layer "F.Fab")
		)
		(fp_line
			(start -0.67945 0.3048)
			(end -0.67945 -0.305054)
			(stroke
				(width 0.1)
				(type default)
			)
			(layer "F.Fab")
		)
		(fp_line
			(start -0.12065 -0.305054)
			(end -0.12065 -0.2794)
			(stroke
				(width 0.1)
				(type default)
			)
			(layer "F.Fab")
		)
		(fp_line
			(start -0.12065 -0.2794)
			(end 0.12065 -0.2794)
			(stroke
				(width 0.1)
				(type default)
			)
			(layer "F.Fab")
		)
		(fp_line
			(start -0.12065 0.2794)
			(end -0.12065 0.3048)
			(stroke
				(width 0.1)
				(type default)
			)
			(layer "F.Fab")
		)
		(fp_line
			(start -0.12065 0.3048)
			(end -0.67945 0.3048)
			(stroke
				(width 0.1)
				(type default)
			)
			(layer "F.Fab")
		)
		(fp_line
			(start 0.120396 0.2794)
			(end -0.12065 0.2794)
			(stroke
				(width 0.1)
				(type default)
			)
			(layer "F.Fab")
		)
		(fp_line
			(start 0.120396 0.3048)
			(end 0.120396 0.2794)
			(stroke
				(width 0.1)
				(type default)
			)
			(layer "F.Fab")
		)
		(fp_line
			(start 0.12065 -0.3048)
			(end 0.67945 -0.3048)
			(stroke
				(width 0.1)
				(type default)
			)
			(layer "F.Fab")
		)
		(fp_line
			(start 0.12065 -0.2794)
			(end 0.12065 -0.3048)
			(stroke
				(width 0.1)
				(type default)
			)
			(layer "F.Fab")
		)
		(fp_line
			(start 0.67945 -0.3048)
			(end 0.67945 0.3048)
			(stroke
				(width 0.1)
				(type default)
			)
			(layer "F.Fab")
		)
		(fp_line
			(start 0.67945 0.3048)
			(end 0.120396 0.3048)
			(stroke
				(width 0.1)
				(type default)
			)
			(layer "F.Fab")
		)
		(pad "1" smd circle
			(at -0.40005 0)
			(size 0 0)
			(layers "F.Cu" "F.Mask" "F.Paste")
			(net "RST_BMC_SELF_HW_D_C")
		)
		(pad "2" smd circle
			(at 0.40005 0)
			(size 0 0)
			(layers "F.Cu" "F.Mask" "F.Paste")
			(net "GND")
		)
	)
)
